# S9S_MB_2U (Grand Teton) — schematic netlist excerpt (pin names and nets, part order shuffled) for the footprints in the layout excerpt that follows; sources: Cadence DE-HDL packaged netlist, KiCad conversion of 03242023_DA0F0TMBIJ0_F0T_Motherboard_J_brd_V01_OCP.brd

PC1321  Q_CAP  0.068UF 16V 10% EMPTY  pkg 0402  page 163 : A = P3V3_OCP_DVDT_2 ; B = GND
C1831  Q_CAP  0.1UF 25V 10% X7R  pkg 0402  page 159 : A = P12V_OCP_V3_2 ; B = GND

(kicad_pcb
	(version 20260206)
	(generator "pcbnew")
	(generator_version "10.0")
	(general
		(thickness 1.6)
		(legacy_teardrops no)
	)
	(paper "A4")
	(title_block
		(title "03242023_DA0F0TMBIJ0_F0T_Motherboard_J_brd_V01_OCP.brd")
		(comment 1 "Grand Teton / footprints 1772-1773 of 6105")
	)
	(layers
		(0 "F.Cu" signal "TOP")
		(4 "In1.Cu" signal "GND")
		(6 "In2.Cu" signal "IN1")
		(8 "In3.Cu" signal "GND1")
		(10 "In4.Cu" signal "IN2")
		(12 "In5.Cu" signal "GND2")
		(14 "In6.Cu" signal "IN3")
		(16 "In7.Cu" signal "GND3")
		(18 "In8.Cu" signal "VCC")
		(20 "In9.Cu" signal "VCC1")
		(22 "In10.Cu" signal "GND4")
		(24 "In11.Cu" signal "IN4")
		(26 "In12.Cu" signal "GND5")
		(28 "In13.Cu" signal "IN5")
		(30 "In14.Cu" signal "GND6")
		(32 "In15.Cu" signal "IN6")
		(34 "In16.Cu" signal "GND7")
		(2 "B.Cu" signal "BOTTOM")
		(9 "F.Adhes" user "F.Adhesive")
		(11 "B.Adhes" user "B.Adhesive")
		(13 "F.Paste" user "Package Geometry/Pastemask Top")
		(15 "B.Paste" user "Package Geometry/Pastemask Bottom")
		(5 "F.SilkS" user "Ref Des/Silkscreen Top")
		(7 "B.SilkS" user "Ref Des/Silkscreen Bottom")
		(1 "F.Mask" user "Board Geometry/Soldermask Top")
		(3 "B.Mask" user "Board Geometry/Soldermask Bottom")
		(17 "Dwgs.User" user "User.Drawings")
		(19 "Cmts.User" user "User.Comments")
		(21 "Eco1.User" user "User.Eco1")
		(23 "Eco2.User" user "User.Eco2")
		(25 "Edge.Cuts" user "Board Geometry/Outline")
		(27 "Margin" user)
		(31 "F.CrtYd" user "Package Geometry/Place Bound Top")
		(29 "B.CrtYd" user "Package Geometry/Place Bound Bottom")
		(35 "F.Fab" user "Ref Des/Assembly Top")
		(33 "B.Fab" user "Ref Des/Assembly Bottom")
	)
	(footprint ""
		(layer "F.Cu")
		(at 66.162174 -16.37157 180)
		(property "Reference" "C1831"
			(at 0 0 180)
			(layer "F.SilkS")
			(hide yes)
			(effects
				(font
					(size 1.27 1.27)
				)
			)
		)
		(property "Value" ""
			(at 0 0 180)
			(layer "F.Fab")
			(effects
				(font
					(size 1.27 1.27)
				)
			)
		)
		(duplicate_pad_numbers_are_jumpers no)
		(fp_line
			(start 0.7874 0.4064)
			(end -0.7874 0.4064)
			(stroke
				(width 0.1524)
				(type default)
			)
			(layer "F.SilkS")
		)
		(fp_line
			(start 0.7874 -0.4064)
			(end 0.7874 0.4064)
			(stroke
				(width 0.1524)
				(type default)
			)
			(layer "F.SilkS")
		)
		(fp_line
			(start -0.7874 0.4064)
			(end -0.7874 -0.4064)
			(stroke
				(width 0.1524)
				(type default)
			)
			(layer "F.SilkS")
		)
		(fp_line
			(start -0.7874 -0.4064)
			(end 0.7874 -0.4064)
			(stroke
				(width 0.1524)
				(type default)
			)
			(layer "F.SilkS")
		)
		(fp_line
			(start 0.67945 0.3048)
			(end 0.120396 0.3048)
			(stroke
				(width 0.1)
				(type default)
			)
			(layer "F.Fab")
		)
		(fp_line
			(start 0.67945 -0.3048)
			(end 0.67945 0.3048)
			(stroke
				(width 0.1)
				(type default)
			)
			(layer "F.Fab")
		)
		(fp_line
			(start 0.12065 -0.2794)
			(end 0.12065 -0.3048)
			(stroke
				(width 0.1)
				(type default)
			)
			(layer "F.Fab")
		)
		(fp_line
			(start 0.12065 -0.3048)
			(end 0.67945 -0.3048)
			(stroke
				(width 0.1)
				(type default)
			)
			(layer "F.Fab")
		)
		(fp_line
			(start 0.120396 0.3048)
			(end 0.120396 0.2794)
			(stroke
				(width 0.1)
				(type default)
			)
			(layer "F.Fab")
		)
		(fp_line
			(start 0.120396 0.2794)
			(end -0.12065 0.2794)
			(stroke
				(width 0.1)
				(type default)
			)
			(layer "F.Fab")
		)
		(fp_line
			(start -0.12065 0.3048)
			(end -0.67945 0.3048)
			(stroke
				(width 0.1)
				(type default)
			)
			(layer "F.Fab")
		)
		(fp_line
			(start -0.12065 0.2794)
			(end -0.12065 0.3048)
			(stroke
				(width 0.1)
				(type default)
			)
			(layer "F.Fab")
		)
		(fp_line
			(start -0.12065 -0.2794)
			(end 0.12065 -0.2794)
			(stroke
				(width 0.1)
				(type default)
			)
			(layer "F.Fab")
		)
		(fp_line
			(start -0.12065 -0.305054)
			(end -0.12065 -0.2794)
			(stroke
				(width 0.1)
				(type default)
			)
			(layer "F.Fab")
		)
		(fp_line
			(start -0.67945 0.3048)
			(end -0.67945 -0.305054)
			(stroke
				(width 0.1)
				(type default)
			)
			(layer "F.Fab")
		)
		(fp_line
			(start -0.67945 -0.305054)
			(end -0.12065 -0.305054)
			(stroke
				(width 0.1)
				(type default)
			)
			(layer "F.Fab")
		)
		(pad "1" smd circle
			(at -0.40005 0 180)
			(size 0 0)
			(layers "F.Cu" "F.Mask" "F.Paste")
			(net "P12V_OCP_V3_2")
		)
		(pad "2" smd circle
			(at 0.40005 0 180)
			(size 0 0)
			(layers "F.Cu" "F.Mask" "F.Paste")
			(net "GND")
		)
	)
	(footprint ""
		(layer "F.Cu")
		(at 66.86296 -61.158628 90)
		(property "Reference" "PC1321"
			(at 0 0 90)
			(layer "F.SilkS")
			(hide yes)
			(effects
				(font
					(size 1.27 1.27)
				)
			)
		)
		(property "Value" ""
			(at 0 0 90)
			(layer "F.Fab")
			(effects
				(font
					(size 1.27 1.27)
				)
			)
		)
		(duplicate_pad_numbers_are_jumpers no)
		(fp_line
			(start 0.7874 -0.4064)
			(end 0.7874 0.4064)
			(stroke
				(width 0.1524)
				(type default)
			)
			(layer "F.SilkS")
		)
		(fp_line
			(start -0.7874 -0.4064)
			(end 0.7874 -0.4064)
			(stroke
				(width 0.1524)
				(type default)
			)
			(layer "F.SilkS")
		)
		(fp_line
			(start 0.7874 0.4064)
			(end -0.7874 0.4064)
			(stroke
				(width 0.1524)
				(type default)
			)
			(layer "F.SilkS")
		)
		(fp_line
			(start -0.7874 0.4064)
			(end -0.7874 -0.4064)
			(stroke
				(width 0.1524)
				(type default)
			)
			(layer "F.SilkS")
		)
		(fp_line
			(start -0.12065 -0.305054)
			(end -0.12065 -0.2794)
			(stroke
				(width 0.1)
				(type default)
			)
			(layer "F.Fab")
		)
		(fp_line
			(start -0.67945 -0.305054)
			(end -0.12065 -0.305054)
			(stroke
				(width 0.1)
				(type default)
			)
			(layer "F.Fab")
		)
		(fp_line
			(start 0.67945 -0.3048)
			(end 0.67945 0.3048)
			(stroke
				(width 0.1)
				(type default)
			)
			(layer "F.Fab")
		)
		(fp_line
			(start 0.12065 -0.3048)
			(end 0.67945 -0.3048)
			(stroke
				(width 0.1)
				(type default)
			)
			(layer "F.Fab")
		)
		(fp_line
			(start 0.12065 -0.2794)
			(end 0.12065 -0.3048)
			(stroke
				(width 0.1)
				(type default)
			)
			(layer "F.Fab")
		)
		(fp_line
			(start -0.12065 -0.2794)
			(end 0.12065 -0.2794)
			(stroke
				(width 0.1)
				(type default)
			)
			(layer "F.Fab")
		)
		(fp_line
			(start 0.120396 0.2794)
			(end -0.12065 0.2794)
			(stroke
				(width 0.1)
				(type default)
			)
			(layer "F.Fab")
		)
		(fp_line
			(start -0.12065 0.2794)
			(end -0.12065 0.3048)
			(stroke
				(width 0.1)
				(type default)
			)
			(layer "F.Fab")
		)
		(fp_line
			(start 0.67945 0.3048)
			(end 0.120396 0.3048)
			(stroke
				(width 0.1)
				(type default)
			)
			(layer "F.Fab")
		)
		(fp_line
			(start 0.120396 0.3048)
			(end 0.120396 0.2794)
			(stroke
				(width 0.1)
				(type default)
			)
			(layer "F.Fab")
		)
		(fp_line
			(start -0.12065 0.3048)
			(end -0.67945 0.3048)
			(stroke
				(width 0.1)
				(type default)
			)
			(layer "F.Fab")
		)
		(fp_line
			(start -0.67945 0.3048)
			(end -0.67945 -0.305054)
			(stroke
				(width 0.1)
				(type default)
			)
			(layer "F.Fab")
		)
		(pad "1" smd circle
			(at -0.40005 0 90)
			(size 0 0)
			(layers "F.Cu" "F.Mask" "F.Paste")
			(net "P3V3_OCP_DVDT_2")
		)
		(pad "2" smd circle
			(at 0.40005 0 90)
			(size 0 0)
			(layers "F.Cu" "F.Mask" "F.Paste")
			(net "GND")
		)
	)
)
